# S9S_MB_2U (Grand Teton) — schematic netlist excerpt (pin names and nets, part order shuffled) for the footprints in the layout excerpt that follows; sources: Cadence DE-HDL packaged netlist, KiCad conversion of 03242023_DA0F0TMBIJ0_F0T_Motherboard_J_brd_V01_OCP.brd

PL64  Q_INDUCTOR  BLM18SN220TN1D/8000MA IND  pkg SMLF  page 258 : \1\ = P12V_AUX ; \2\ = SW_P5V_AUX_FLT

(kicad_pcb
	(version 20260206)
	(generator "pcbnew")
	(generator_version "10.0")
	(general
		(thickness 1.6)
		(legacy_teardrops no)
	)
	(paper "A4")
	(title_block
		(title "03242023_DA0F0TMBIJ0_F0T_Motherboard_J_brd_V01_OCP.brd")
		(comment 1 "Grand Teton / footprints 2333-2333 of 6105")
	)
	(layers
		(0 "F.Cu" signal "TOP")
		(4 "In1.Cu" signal "GND")
		(6 "In2.Cu" signal "IN1")
		(8 "In3.Cu" signal "GND1")
		(10 "In4.Cu" signal "IN2")
		(12 "In5.Cu" signal "GND2")
		(14 "In6.Cu" signal "IN3")
		(16 "In7.Cu" signal "GND3")
		(18 "In8.Cu" signal "VCC")
		(20 "In9.Cu" signal "VCC1")
		(22 "In10.Cu" signal "GND4")
		(24 "In11.Cu" signal "IN4")
		(26 "In12.Cu" signal "GND5")
		(28 "In13.Cu" signal "IN5")
		(30 "In14.Cu" signal "GND6")
		(32 "In15.Cu" signal "IN6")
		(34 "In16.Cu" signal "GND7")
		(2 "B.Cu" signal "BOTTOM")
		(9 "F.Adhes" user "F.Adhesive")
		(11 "B.Adhes" user "B.Adhesive")
		(13 "F.Paste" user "Package Geometry/Pastemask Top")
		(15 "B.Paste" user "Package Geometry/Pastemask Bottom")
		(5 "F.SilkS" user "Ref Des/Silkscreen Top")
		(7 "B.SilkS" user "Ref Des/Silkscreen Bottom")
		(1 "F.Mask" user "Board Geometry/Soldermask Top")
		(3 "B.Mask" user "Board Geometry/Soldermask Bottom")
		(17 "Dwgs.User" user "User.Drawings")
		(19 "Cmts.User" user "User.Comments")
		(21 "Eco1.User" user "User.Eco1")
		(23 "Eco2.User" user "User.Eco2")
		(25 "Edge.Cuts" user "Board Geometry/Outline")
		(27 "Margin" user)
		(31 "F.CrtYd" user "Package Geometry/Place Bound Top")
		(29 "B.CrtYd" user "Package Geometry/Place Bound Bottom")
		(35 "F.Fab" user "Ref Des/Assembly Top")
		(33 "B.Fab" user "Ref Des/Assembly Bottom")
	)
	(footprint ""
		(layer "F.Cu")
		(at 465.036408 -382.750314 90)
		(property "Reference" "PL64"
			(at 0 0 90)
			(layer "F.SilkS")
			(hide yes)
			(effects
				(font
					(size 1.27 1.27)
				)
			)
		)
		(property "Value" ""
			(at 0 0 90)
			(layer "F.Fab")
			(effects
				(font
					(size 1.27 1.27)
				)
			)
		)
		(duplicate_pad_numbers_are_jumpers no)
		(fp_line
			(start -1.27 -0.5842)
			(end 1.27 -0.5842)
			(stroke
				(width 0.1524)
				(type default)
			)
			(layer "F.SilkS")
		)
		(fp_line
			(start -1.27 -0.5588)
			(end -1.27 -0.5842)
			(stroke
				(width 0.1524)
				(type default)
			)
			(layer "F.SilkS")
		)
		(fp_line
			(start 1.27 0.5842)
			(end 1.27 -0.5842)
			(stroke
				(width 0.1524)
				(type default)
			)
			(layer "F.SilkS")
		)
		(fp_line
			(start 1.27 0.5842)
			(end -1.27 0.5842)
			(stroke
				(width 0.1524)
				(type default)
			)
			(layer "F.SilkS")
		)
		(fp_line
			(start 0.127 0.5842)
			(end 0.127 -0.5842)
			(stroke
				(width 0.1524)
				(type default)
			)
			(layer "F.SilkS")
		)
		(fp_line
			(start -0.127 0.5842)
			(end -0.127 -0.5842)
			(stroke
				(width 0.1524)
				(type default)
			)
			(layer "F.SilkS")
		)
		(fp_line
			(start -1.27 0.5842)
			(end -1.27 -0.5842)
			(stroke
				(width 0.1524)
				(type default)
			)
			(layer "F.SilkS")
		)
		(fp_line
			(start 0.9144 -0.508)
			(end 0.9144 -0.406654)
			(stroke
				(width 0.1)
				(type default)
			)
			(layer "F.Fab")
		)
		(fp_line
			(start -0.9144 -0.508)
			(end 0.9144 -0.508)
			(stroke
				(width 0.1)
				(type default)
			)
			(layer "F.Fab")
		)
		(fp_line
			(start 1.1938 -0.406654)
			(end 1.1938 0.4064)
			(stroke
				(width 0.1)
				(type default)
			)
			(layer "F.Fab")
		)
		(fp_line
			(start 0.9144 -0.406654)
			(end 1.1938 -0.406654)
			(stroke
				(width 0.1)
				(type default)
			)
			(layer "F.Fab")
		)
		(fp_line
			(start -0.9144 -0.406654)
			(end -0.9144 -0.508)
			(stroke
				(width 0.1)
				(type default)
			)
			(layer "F.Fab")
		)
		(fp_line
			(start -1.194308 -0.406654)
			(end -0.9144 -0.406654)
			(stroke
				(width 0.1)
				(type default)
			)
			(layer "F.Fab")
		)
		(fp_line
			(start 1.1938 0.4064)
			(end 0.9144 0.4064)
			(stroke
				(width 0.1)
				(type default)
			)
			(layer "F.Fab")
		)
		(fp_line
			(start 0.9144 0.4064)
			(end 0.9144 0.508)
			(stroke
				(width 0.1)
				(type default)
			)
			(layer "F.Fab")
		)
		(fp_line
			(start -0.9144 0.406654)
			(end -1.194308 0.406654)
			(stroke
				(width 0.1)
				(type default)
			)
			(layer "F.Fab")
		)
		(fp_line
			(start -1.194308 0.406654)
			(end -1.194308 -0.406654)
			(stroke
				(width 0.1)
				(type default)
			)
			(layer "F.Fab")
		)
		(fp_line
			(start 0.9144 0.508)
			(end -0.9144 0.508)
			(stroke
				(width 0.1)
				(type default)
			)
			(layer "F.Fab")
		)
		(fp_line
			(start -0.9144 0.508)
			(end -0.9144 0.406654)
			(stroke
				(width 0.1)
				(type default)
			)
			(layer "F.Fab")
		)
		(pad "1" smd rect
			(at -0.7366 0)
			(size 0.7112 0.8128)
			(layers "F.Cu" "F.Mask" "F.Paste")
			(net "P12V_AUX")
		)
		(pad "2" smd rect
			(at 0.7366 0)
			(size 0.7112 0.8128)
			(layers "F.Cu" "F.Mask" "F.Paste")
			(net "SW_P5V_AUX_FLT")
		)
	)
)
